FILE_TYPE=LIBRARY_PARTS;
primitive 'CONN8_H62179001','CONN8_H62179001_TH','CONN8_H62179001_PIP';
  pin
    'IO1':
      PIN_NUMBER='(1)';
      BIDIRECTIONAL='TRUE';
      INPUT_LOAD='(-0.01,0.01)';
      OUTPUT_LOAD='(1.0,-1.0)';
    'IO2':
      PIN_NUMBER='(2)';
      BIDIRECTIONAL='TRUE';
      INPUT_LOAD='(-0.01,0.01)';
      OUTPUT_LOAD='(1.0,-1.0)';
    'IO3':
      PIN_NUMBER='(3)';
      BIDIRECTIONAL='TRUE';
      INPUT_LOAD='(-0.01,0.01)';
      OUTPUT_LOAD='(1.0,-1.0)';
    'IO4':
      PIN_NUMBER='(4)';
      BIDIRECTIONAL='TRUE';
      INPUT_LOAD='(-0.01,0.01)';
      OUTPUT_LOAD='(1.0,-1.0)';
    'IO5':
      PIN_NUMBER='(5)';
      BIDIRECTIONAL='TRUE';
      INPUT_LOAD='(-0.01,0.01)';
      OUTPUT_LOAD='(1.0,-1.0)';
    'IO6':
      PIN_NUMBER='(6)';
      BIDIRECTIONAL='TRUE';
      INPUT_LOAD='(-0.01,0.01)';
      OUTPUT_LOAD='(1.0,-1.0)';
    'IO7':
      PIN_NUMBER='(7)';
      BIDIRECTIONAL='TRUE';
      INPUT_LOAD='(-0.01,0.01)';
      OUTPUT_LOAD='(1.0,-1.0)';
    'IO8':
      PIN_NUMBER='(8)';
      BIDIRECTIONAL='TRUE';
      INPUT_LOAD='(-0.01,0.01)';
      OUTPUT_LOAD='(1.0,-1.0)';
  end_pin;
  body
    PART_NAME='CONN8_H62179001';
    PHYS_DES_PREFIX='J';
  end_body;
end_primitive;

END.
